(kicad_pcb
	(version 20260206)
	(generator "pcbnew")
	(generator_version "10.0")
	(general
		(thickness 1.6)
		(legacy_teardrops no)
	)
	(paper "A4")
	(title_block
		(title "v1-chassis-manager — T6M_CM_d_v01_1031_1645.brd")
		(comment 1 "Open CloudServer (Microsoft) / footprints 1728-1737 of 2512")
	)
	(layers
		(0 "F.Cu" signal "TOP")
		(4 "In1.Cu" signal "GND1")
		(6 "In2.Cu" signal "IN1")
		(8 "In3.Cu" signal "VCC1")
		(10 "In4.Cu" signal "VCC2")
		(12 "In5.Cu" signal "GND2")
		(14 "In6.Cu" signal "IN2")
		(16 "In7.Cu" signal "IN3")
		(18 "In8.Cu" signal "GND3")
		(2 "B.Cu" signal "BOTTOM")
		(9 "F.Adhes" user "F.Adhesive")
		(11 "B.Adhes" user "B.Adhesive")
		(13 "F.Paste" user "Package Geometry/Pastemask Top")
		(15 "B.Paste" user "Package Geometry/Pastemask Bottom")
		(5 "F.SilkS" user "Ref Des/Silkscreen Top")
		(7 "B.SilkS" user "Ref Des/Silkscreen Bottom")
		(1 "F.Mask" user "Board Geometry/Soldermask Top")
		(3 "B.Mask" user "Board Geometry/Soldermask Bottom")
		(17 "Dwgs.User" user "User.Drawings")
		(19 "Cmts.User" user "User.Comments")
		(21 "Eco1.User" user "User.Eco1")
		(23 "Eco2.User" user "User.Eco2")
		(25 "Edge.Cuts" user "Board Geometry/Outline")
		(27 "Margin" user)
		(31 "F.CrtYd" user "Package Geometry/Place Bound Top")
		(29 "B.CrtYd" user "Package Geometry/Place Bound Bottom")
		(35 "F.Fab" user "Ref Des/Assembly Top")
		(33 "B.Fab" user "Ref Des/Assembly Bottom")
	)
	(footprint ""
		(layer "B.Cu")
		(at 81.02727 -21.09724 90)
		(property "Reference" "C165"
			(at -5.806948 -0.770128 270)
			(unlocked yes)
			(layer "B.SilkS")
			(effects
				(font
					(size 0.7874 0.5842)
					(thickness 0.1524)
				)
				(justify left mirror)
			)
		)
		(property "Value" ""
			(at 0 0 90)
			(layer "B.Fab")
			(effects
				(font
					(size 1.27 1.27)
				)
				(justify mirror)
			)
		)
		(duplicate_pad_numbers_are_jumpers no)
		(fp_line
			(start 0.7874 -0.4064)
			(end -0.7874 -0.4064)
			(stroke
				(width 0.1524)
				(type default)
			)
			(layer "B.SilkS")
		)
		(fp_line
			(start -0.7874 -0.4064)
			(end -0.7874 0.4064)
			(stroke
				(width 0.1524)
				(type default)
			)
			(layer "B.SilkS")
		)
		(fp_line
			(start 0 0.381)
			(end 0 -0.381)
			(stroke
				(width 0.1524)
				(type default)
			)
			(layer "B.SilkS")
		)
		(fp_line
			(start 0.7874 0.4064)
			(end 0.7874 -0.4064)
			(stroke
				(width 0.1524)
				(type default)
			)
			(layer "B.SilkS")
		)
		(fp_line
			(start -0.7874 0.4064)
			(end 0.7874 0.4064)
			(stroke
				(width 0.1524)
				(type default)
			)
			(layer "B.SilkS")
		)
		(fp_poly
			(pts
				(xy 0.5334 0.254) (xy 0.635 0.254) (xy 0.635 0.2286) (xy 0.635 -0.254) (xy 0.5334 -0.254) (xy 0.5334 -0.2794)
				(xy -0.5334 -0.2794) (xy -0.5334 -0.254) (xy -0.635 -0.254) (xy -0.635 0.254) (xy -0.5334 0.254)
				(xy -0.5334 0.2794) (xy 0.508 0.2794) (xy 0.5334 0.2794)
			)
			(stroke
				(width 0)
				(type default)
			)
			(fill no)
			(layer "B.CrtYd")
		)
		(pad "1" smd rect
			(at -0.40005 0 270)
			(size 0.4572 0.508)
			(layers "B.Cu" "B.Mask" "B.Paste")
			(net "PV_VDDR_NODE1")
		)
		(pad "2" smd rect
			(at 0.40005 0 270)
			(size 0.4572 0.508)
			(layers "B.Cu" "B.Mask" "B.Paste")
			(net "GND")
		)
	)
	(footprint ""
		(layer "B.Cu")
		(at 61.089286 -146.419062 90)
		(property "Reference" "R292"
			(at 0.935736 -0.36957 270)
			(unlocked yes)
			(layer "B.SilkS")
			(effects
				(font
					(size 0.7874 0.5842)
					(thickness 0.1524)
				)
				(justify left mirror)
			)
		)
		(property "Value" ""
			(at 0 0 90)
			(layer "B.Fab")
			(effects
				(font
					(size 1.27 1.27)
				)
				(justify mirror)
			)
		)
		(duplicate_pad_numbers_are_jumpers no)
		(fp_line
			(start 0.7874 -0.4064)
			(end -0.7874 -0.4064)
			(stroke
				(width 0.1524)
				(type default)
			)
			(layer "B.SilkS")
		)
		(fp_line
			(start -0.7874 -0.4064)
			(end -0.7874 0.4064)
			(stroke
				(width 0.1524)
				(type default)
			)
			(layer "B.SilkS")
		)
		(fp_line
			(start 0.7874 0.4064)
			(end 0.7874 -0.4064)
			(stroke
				(width 0.1524)
				(type default)
			)
			(layer "B.SilkS")
		)
		(fp_line
			(start -0.7874 0.4064)
			(end 0.7874 0.4064)
			(stroke
				(width 0.1524)
				(type default)
			)
			(layer "B.SilkS")
		)
		(fp_poly
			(pts
				(xy 0.508 0.2794) (xy 0.508 0.2286) (xy 0.635 0.2286) (xy 0.635 -0.254) (xy 0.5334 -0.254) (xy 0.5334 -0.2794)
				(xy -0.5334 -0.2794) (xy -0.5334 -0.254) (xy -0.635 -0.254) (xy -0.635 0.254) (xy -0.5334 0.254)
				(xy -0.5334 0.2794)
			)
			(stroke
				(width 0)
				(type default)
			)
			(fill no)
			(layer "B.CrtYd")
		)
		(pad "1" smd rect
			(at -0.40005 0 270)
			(size 0.4572 0.508)
			(layers "B.Cu" "B.Mask" "B.Paste")
			(net "BMC_NODE1_GFX_RED")
		)
		(pad "2" smd rect
			(at 0.40005 0 270)
			(size 0.4572 0.508)
			(layers "B.Cu" "B.Mask" "B.Paste")
			(net "GND")
		)
	)
	(footprint ""
		(layer "B.Cu")
		(at 127.921512 -144.83461 90)
		(property "Reference" "C932"
			(at 0.03302 2.38633 270)
			(unlocked yes)
			(layer "B.SilkS")
			(effects
				(font
					(size 0.7874 0.5842)
					(thickness 0.1524)
				)
				(justify left mirror)
			)
		)
		(property "Value" ""
			(at 0 0 90)
			(layer "B.Fab")
			(effects
				(font
					(size 1.27 1.27)
				)
				(justify mirror)
			)
		)
		(duplicate_pad_numbers_are_jumpers no)
		(fp_line
			(start 0.7874 -0.4064)
			(end -0.7874 -0.4064)
			(stroke
				(width 0.1524)
				(type default)
			)
			(layer "B.SilkS")
		)
		(fp_line
			(start -0.7874 -0.4064)
			(end -0.7874 0.4064)
			(stroke
				(width 0.1524)
				(type default)
			)
			(layer "B.SilkS")
		)
		(fp_line
			(start 0 0.381)
			(end 0 -0.381)
			(stroke
				(width 0.1524)
				(type default)
			)
			(layer "B.SilkS")
		)
		(fp_line
			(start 0.7874 0.4064)
			(end 0.7874 -0.4064)
			(stroke
				(width 0.1524)
				(type default)
			)
			(layer "B.SilkS")
		)
		(fp_line
			(start -0.7874 0.4064)
			(end 0.7874 0.4064)
			(stroke
				(width 0.1524)
				(type default)
			)
			(layer "B.SilkS")
		)
		(fp_poly
			(pts
				(xy 0.5334 0.254) (xy 0.635 0.254) (xy 0.635 0.2286) (xy 0.635 -0.254) (xy 0.5334 -0.254) (xy 0.5334 -0.2794)
				(xy -0.5334 -0.2794) (xy -0.5334 -0.254) (xy -0.635 -0.254) (xy -0.635 0.254) (xy -0.5334 0.254)
				(xy -0.5334 0.2794) (xy 0.508 0.2794) (xy 0.5334 0.2794)
			)
			(stroke
				(width 0)
				(type default)
			)
			(fill no)
			(layer "B.CrtYd")
		)
		(pad "1" smd rect
			(at -0.40005 0 270)
			(size 0.4572 0.508)
			(layers "B.Cu" "B.Mask" "B.Paste")
			(net "P1V0_PCI_SW_A")
		)
		(pad "2" smd rect
			(at 0.40005 0 270)
			(size 0.4572 0.508)
			(layers "B.Cu" "B.Mask" "B.Paste")
			(net "GND")
		)
	)
	(footprint ""
		(layer "B.Cu")
		(at 143.122396 -59.96813 90)
		(property "Reference" "C341"
			(at 1.050036 -0.288798 270)
			(unlocked yes)
			(layer "B.SilkS")
			(effects
				(font
					(size 0.7874 0.5842)
					(thickness 0.1524)
				)
				(justify left mirror)
			)
		)
		(property "Value" ""
			(at 0 0 90)
			(layer "B.Fab")
			(effects
				(font
					(size 1.27 1.27)
				)
				(justify mirror)
			)
		)
		(duplicate_pad_numbers_are_jumpers no)
		(fp_line
			(start 0.7874 -0.4064)
			(end -0.7874 -0.4064)
			(stroke
				(width 0.1524)
				(type default)
			)
			(layer "B.SilkS")
		)
		(fp_line
			(start -0.7874 -0.4064)
			(end -0.7874 0.4064)
			(stroke
				(width 0.1524)
				(type default)
			)
			(layer "B.SilkS")
		)
		(fp_line
			(start 0 0.381)
			(end 0 -0.381)
			(stroke
				(width 0.1524)
				(type default)
			)
			(layer "B.SilkS")
		)
		(fp_line
			(start 0.7874 0.4064)
			(end 0.7874 -0.4064)
			(stroke
				(width 0.1524)
				(type default)
			)
			(layer "B.SilkS")
		)
		(fp_line
			(start -0.7874 0.4064)
			(end 0.7874 0.4064)
			(stroke
				(width 0.1524)
				(type default)
			)
			(layer "B.SilkS")
		)
		(fp_poly
			(pts
				(xy 0.5334 0.254) (xy 0.635 0.254) (xy 0.635 0.2286) (xy 0.635 -0.254) (xy 0.5334 -0.254) (xy 0.5334 -0.2794)
				(xy -0.5334 -0.2794) (xy -0.5334 -0.254) (xy -0.635 -0.254) (xy -0.635 0.254) (xy -0.5334 0.254)
				(xy -0.5334 0.2794) (xy 0.508 0.2794) (xy 0.5334 0.2794)
			)
			(stroke
				(width 0)
				(type default)
			)
			(fill no)
			(layer "B.CrtYd")
		)
		(pad "1" smd rect
			(at -0.40005 0 270)
			(size 0.4572 0.508)
			(layers "B.Cu" "B.Mask" "B.Paste")
			(net "P1V0_SATA")
		)
		(pad "2" smd rect
			(at 0.40005 0 270)
			(size 0.4572 0.508)
			(layers "B.Cu" "B.Mask" "B.Paste")
			(net "GND")
		)
	)
	(footprint ""
		(layer "B.Cu")
		(at 142.07236 -170.981624 180)
		(property "Reference" "R728"
			(at 1.275588 0.274828 0)
			(unlocked yes)
			(layer "B.SilkS")
			(effects
				(font
					(size 0.7874 0.5842)
					(thickness 0.1524)
				)
				(justify left mirror)
			)
		)
		(property "Value" ""
			(at 0 0 0)
			(layer "B.Fab")
			(effects
				(font
					(size 1.27 1.27)
				)
				(justify mirror)
			)
		)
		(duplicate_pad_numbers_are_jumpers no)
		(fp_line
			(start 0.7874 0.4064)
			(end 0.7874 -0.4064)
			(stroke
				(width 0.1524)
				(type default)
			)
			(layer "B.SilkS")
		)
		(fp_line
			(start 0.7874 -0.4064)
			(end -0.7874 -0.4064)
			(stroke
				(width 0.1524)
				(type default)
			)
			(layer "B.SilkS")
		)
		(fp_line
			(start -0.7874 0.4064)
			(end 0.7874 0.4064)
			(stroke
				(width 0.1524)
				(type default)
			)
			(layer "B.SilkS")
		)
		(fp_line
			(start -0.7874 -0.4064)
			(end -0.7874 0.4064)
			(stroke
				(width 0.1524)
				(type default)
			)
			(layer "B.SilkS")
		)
		(fp_poly
			(pts
				(xy 0.508 0.2794) (xy 0.508 0.2286) (xy 0.635 0.2286) (xy 0.635 -0.254) (xy 0.5334 -0.254) (xy 0.5334 -0.2794)
				(xy -0.5334 -0.2794) (xy -0.5334 -0.254) (xy -0.635 -0.254) (xy -0.635 0.254) (xy -0.5334 0.254)
				(xy -0.5334 0.2794)
			)
			(stroke
				(width 0)
				(type default)
			)
			(fill no)
			(layer "B.CrtYd")
		)
		(pad "1" smd rect
			(at -0.40005 0)
			(size 0.4572 0.508)
			(layers "B.Cu" "B.Mask" "B.Paste")
			(net "T9_NODE1_EN")
		)
		(pad "2" smd rect
			(at 0.40005 0)
			(size 0.4572 0.508)
			(layers "B.Cu" "B.Mask" "B.Paste")
			(net "P5V_NODE1")
		)
	)
	(footprint ""
		(layer "B.Cu")
		(at 152.76576 -184.951624 90)
		(property "Reference" "R891"
			(at 4.281424 -2.31013 270)
			(unlocked yes)
			(layer "B.SilkS")
			(effects
				(font
					(size 0.7874 0.5842)
					(thickness 0.1524)
				)
				(justify left mirror)
			)
		)
		(property "Value" ""
			(at 0 0 90)
			(layer "B.Fab")
			(effects
				(font
					(size 1.27 1.27)
				)
				(justify mirror)
			)
		)
		(duplicate_pad_numbers_are_jumpers no)
		(fp_line
			(start 0.7874 -0.4064)
			(end -0.7874 -0.4064)
			(stroke
				(width 0.1524)
				(type default)
			)
			(layer "B.SilkS")
		)
		(fp_line
			(start -0.7874 -0.4064)
			(end -0.7874 0.4064)
			(stroke
				(width 0.1524)
				(type default)
			)
			(layer "B.SilkS")
		)
		(fp_line
			(start 0.7874 0.4064)
			(end 0.7874 -0.4064)
			(stroke
				(width 0.1524)
				(type default)
			)
			(layer "B.SilkS")
		)
		(fp_line
			(start -0.7874 0.4064)
			(end 0.7874 0.4064)
			(stroke
				(width 0.1524)
				(type default)
			)
			(layer "B.SilkS")
		)
		(fp_poly
			(pts
				(xy 0.508 0.2794) (xy 0.508 0.2286) (xy 0.635 0.2286) (xy 0.635 -0.254) (xy 0.5334 -0.254) (xy 0.5334 -0.2794)
				(xy -0.5334 -0.2794) (xy -0.5334 -0.254) (xy -0.635 -0.254) (xy -0.635 0.254) (xy -0.5334 0.254)
				(xy -0.5334 0.2794)
			)
			(stroke
				(width 0)
				(type default)
			)
			(fill no)
			(layer "B.CrtYd")
		)
		(pad "1" smd rect
			(at -0.40005 0 270)
			(size 0.4572 0.508)
			(layers "B.Cu" "B.Mask" "B.Paste")
			(net "T11_NODE3_EN")
		)
		(pad "2" smd rect
			(at 0.40005 0 270)
			(size 0.4572 0.508)
			(layers "B.Cu" "B.Mask" "B.Paste")
			(net "T11_NODE3_EN_R")
		)
	)
	(footprint ""
		(layer "B.Cu")
		(at 33.56229 -127.361188 -90)
		(property "Reference" "C831"
			(at 1.36271 1.55829 270)
			(unlocked yes)
			(layer "B.SilkS")
			(effects
				(font
					(size 0.7874 0.5842)
					(thickness 0.1524)
				)
				(justify left mirror)
			)
		)
		(property "Value" ""
			(at 0 0 90)
			(layer "B.Fab")
			(effects
				(font
					(size 1.27 1.27)
				)
				(justify mirror)
			)
		)
		(duplicate_pad_numbers_are_jumpers no)
		(fp_line
			(start -1.905 0.8636)
			(end 1.905 0.8636)
			(stroke
				(width 0.1524)
				(type default)
			)
			(layer "B.SilkS")
		)
		(fp_line
			(start 1.905 0.8636)
			(end 1.905 -0.8636)
			(stroke
				(width 0.1524)
				(type default)
			)
			(layer "B.SilkS")
		)
		(fp_line
			(start 0 0.8382)
			(end 0 -0.8382)
			(stroke
				(width 0.1524)
				(type default)
			)
			(layer "B.SilkS")
		)
		(fp_line
			(start -1.905 -0.8636)
			(end -1.905 0.8636)
			(stroke
				(width 0.1524)
				(type default)
			)
			(layer "B.SilkS")
		)
		(fp_line
			(start 1.905 -0.8636)
			(end -1.905 -0.8636)
			(stroke
				(width 0.1524)
				(type default)
			)
			(layer "B.SilkS")
		)
		(fp_rect
			(start 1.524 0.7366)
			(end -1.524 -0.7366)
			(stroke
				(width 0)
				(type default)
			)
			(fill no)
			(layer "B.CrtYd")
		)
		(pad "1" smd rect
			(at -0.94996 0 90)
			(size 1.1176 1.3716)
			(layers "B.Cu" "B.Mask" "B.Paste")
			(net "P1V538_BMC_NODE1")
		)
		(pad "2" smd rect
			(at 0.94996 0 90)
			(size 1.1176 1.3716)
			(layers "B.Cu" "B.Mask" "B.Paste")
			(net "GND")
		)
	)
	(footprint ""
		(layer "B.Cu")
		(at 92.68968 -182.494936 -90)
		(property "Reference" "R812"
			(at 2.35204 4.25323 270)
			(unlocked yes)
			(layer "B.SilkS")
			(effects
				(font
					(size 0.7874 0.5842)
					(thickness 0.1524)
				)
				(justify left mirror)
			)
		)
		(property "Value" ""
			(at 0 0 90)
			(layer "B.Fab")
			(effects
				(font
					(size 1.27 1.27)
				)
				(justify mirror)
			)
		)
		(duplicate_pad_numbers_are_jumpers no)
		(fp_line
			(start -0.7874 0.4064)
			(end 0.7874 0.4064)
			(stroke
				(width 0.1524)
				(type default)
			)
			(layer "B.SilkS")
		)
		(fp_line
			(start 0.7874 0.4064)
			(end 0.7874 -0.4064)
			(stroke
				(width 0.1524)
				(type default)
			)
			(layer "B.SilkS")
		)
		(fp_line
			(start -0.7874 -0.4064)
			(end -0.7874 0.4064)
			(stroke
				(width 0.1524)
				(type default)
			)
			(layer "B.SilkS")
		)
		(fp_line
			(start 0.7874 -0.4064)
			(end -0.7874 -0.4064)
			(stroke
				(width 0.1524)
				(type default)
			)
			(layer "B.SilkS")
		)
		(fp_poly
			(pts
				(xy 0.508 0.2794) (xy 0.508 0.2286) (xy 0.635 0.2286) (xy 0.635 -0.254) (xy 0.5334 -0.254) (xy 0.5334 -0.2794)
				(xy -0.5334 -0.2794) (xy -0.5334 -0.254) (xy -0.635 -0.254) (xy -0.635 0.254) (xy -0.5334 0.254)
				(xy -0.5334 0.2794)
			)
			(stroke
				(width 0)
				(type default)
			)
			(fill no)
			(layer "B.CrtYd")
		)
		(pad "1" smd rect
			(at -0.40005 0 90)
			(size 0.4572 0.508)
			(layers "B.Cu" "B.Mask" "B.Paste")
			(net "TACKOVER_EN_N")
		)
		(pad "2" smd rect
			(at 0.40005 0 90)
			(size 0.4572 0.508)
			(layers "B.Cu" "B.Mask" "B.Paste")
			(net "P3V3_NODE1")
		)
	)
	(footprint ""
		(layer "B.Cu")
		(at 68.920106 -21.16328 90)
		(property "Reference" "C155"
			(at -5.872988 -0.810006 270)
			(unlocked yes)
			(layer "B.SilkS")
			(effects
				(font
					(size 0.7874 0.5842)
					(thickness 0.1524)
				)
				(justify left mirror)
			)
		)
		(property "Value" ""
			(at 0 0 90)
			(layer "B.Fab")
			(effects
				(font
					(size 1.27 1.27)
				)
				(justify mirror)
			)
		)
		(duplicate_pad_numbers_are_jumpers no)
		(fp_line
			(start 0.7874 -0.4064)
			(end -0.7874 -0.4064)
			(stroke
				(width 0.1524)
				(type default)
			)
			(layer "B.SilkS")
		)
		(fp_line
			(start -0.7874 -0.4064)
			(end -0.7874 0.4064)
			(stroke
				(width 0.1524)
				(type default)
			)
			(layer "B.SilkS")
		)
		(fp_line
			(start 0 0.381)
			(end 0 -0.381)
			(stroke
				(width 0.1524)
				(type default)
			)
			(layer "B.SilkS")
		)
		(fp_line
			(start 0.7874 0.4064)
			(end 0.7874 -0.4064)
			(stroke
				(width 0.1524)
				(type default)
			)
			(layer "B.SilkS")
		)
		(fp_line
			(start -0.7874 0.4064)
			(end 0.7874 0.4064)
			(stroke
				(width 0.1524)
				(type default)
			)
			(layer "B.SilkS")
		)
		(fp_poly
			(pts
				(xy 0.5334 0.254) (xy 0.635 0.254) (xy 0.635 0.2286) (xy 0.635 -0.254) (xy 0.5334 -0.254) (xy 0.5334 -0.2794)
				(xy -0.5334 -0.2794) (xy -0.5334 -0.254) (xy -0.635 -0.254) (xy -0.635 0.254) (xy -0.5334 0.254)
				(xy -0.5334 0.2794) (xy 0.508 0.2794) (xy 0.5334 0.2794)
			)
			(stroke
				(width 0)
				(type default)
			)
			(fill no)
			(layer "B.CrtYd")
		)
		(pad "1" smd rect
			(at -0.40005 0 270)
			(size 0.4572 0.508)
			(layers "B.Cu" "B.Mask" "B.Paste")
			(net "PV_VDDR_NODE1")
		)
		(pad "2" smd rect
			(at 0.40005 0 270)
			(size 0.4572 0.508)
			(layers "B.Cu" "B.Mask" "B.Paste")
			(net "GND")
		)
	)
	(footprint ""
		(layer "B.Cu")
		(at 37.968428 -133.439662 90)
		(property "Reference" "C226"
			(at -1.92659 -2.218436 270)
			(unlocked yes)
			(layer "B.SilkS")
			(effects
				(font
					(size 0.7874 0.5842)
					(thickness 0.1524)
				)
				(justify left mirror)
			)
		)
		(property "Value" ""
			(at 0 0 90)
			(layer "B.Fab")
			(effects
				(font
					(size 1.27 1.27)
				)
				(justify mirror)
			)
		)
		(duplicate_pad_numbers_are_jumpers no)
		(fp_line
			(start 0.7874 -0.4064)
			(end -0.7874 -0.4064)
			(stroke
				(width 0.1524)
				(type default)
			)
			(layer "B.SilkS")
		)
		(fp_line
			(start -0.7874 -0.4064)
			(end -0.7874 0.4064)
			(stroke
				(width 0.1524)
				(type default)
			)
			(layer "B.SilkS")
		)
		(fp_line
			(start 0 0.381)
			(end 0 -0.381)
			(stroke
				(width 0.1524)
				(type default)
			)
			(layer "B.SilkS")
		)
		(fp_line
			(start 0.7874 0.4064)
			(end 0.7874 -0.4064)
			(stroke
				(width 0.1524)
				(type default)
			)
			(layer "B.SilkS")
		)
		(fp_line
			(start -0.7874 0.4064)
			(end 0.7874 0.4064)
			(stroke
				(width 0.1524)
				(type default)
			)
			(layer "B.SilkS")
		)
		(fp_poly
			(pts
				(xy 0.5334 0.254) (xy 0.635 0.254) (xy 0.635 0.2286) (xy 0.635 -0.254) (xy 0.5334 -0.254) (xy 0.5334 -0.2794)
				(xy -0.5334 -0.2794) (xy -0.5334 -0.254) (xy -0.635 -0.254) (xy -0.635 0.254) (xy -0.5334 0.254)
				(xy -0.5334 0.2794) (xy 0.508 0.2794) (xy 0.5334 0.2794)
			)
			(stroke
				(width 0)
				(type default)
			)
			(fill no)
			(layer "B.CrtYd")
		)
		(pad "1" smd rect
			(at -0.40005 0 270)
			(size 0.4572 0.508)
			(layers "B.Cu" "B.Mask" "B.Paste")
			(net "P1V538_BMC_NODE1")
		)
		(pad "2" smd rect
			(at 0.40005 0 270)
			(size 0.4572 0.508)
			(layers "B.Cu" "B.Mask" "B.Paste")
			(net "P0V75_BMC_VTTREF_NODE1")
		)
	)
)
